FILE_TYPE=LIBRARY_PARTS;
primitive 'PCA9517','PCA9517_SMLF','PCA9517_SM';
  pin
    'EN':
      PIN_NUMBER='(5)';
      INPUT_LOAD='(-0.01,0.01)';
    'SCLA':
      PIN_NUMBER='(2)';
      INPUT_LOAD='(-0.01,0.01)';
    'SCLB':
      PIN_NUMBER='(7)';
      OUTPUT_LOAD='(1.0,-1.0)';
    'SDAA':
      PIN_NUMBER='(3)';
      INPUT_LOAD='(-0.01,0.01)';
    'SDAB':
      PIN_NUMBER='(6)';
      OUTPUT_LOAD='(1.0,-1.0)';
    'VCCA':
      PIN_NUMBER='(1)';
      PIN_TYPE='POWER';
      NO_LOAD_CHECK='BOTH';
      NO_IO_CHECK='BOTH';
      ALLOW_CONNECT='TRUE';
    'VCCB':
      PIN_NUMBER='(8)';
      PIN_TYPE='POWER';
      NO_LOAD_CHECK='BOTH';
      NO_IO_CHECK='BOTH';
      ALLOW_CONNECT='TRUE';
  end_pin;
  body
    POWER_PINS='(GND:4)';
    PART_NAME='PCA9517';
    PHYS_DES_PREFIX='U';
  end_body;
end_primitive;
END.
